# BASEBOARD_FAB2 (Tioga Pass) — schematic parts with pin connectivity, parts 4650–4650 of 4751; source: Cadence DE-HDL packaged netlist (pstxprt.dat, pstxnet.dat, pstchip.dat)

U2D1  SKX_EXT_B  IC  pkg BGA1  page 55  (pins 677-1014 of 3647)
  AW12  DMIMODE_OVERRIDE  BI  = PD_CPU1_DMIMODE_OVERRIDE
  AW14  TEST_15  BI  = PD_CPU1_KSFC_DIS
  AW16  TEST_8  BI  = TP_CPU1_TEST_8
  AW18  TXT_AGENT  IN  = PU_CPU1_TXT_AGENT
  AW20  TEST_9  BI  = TP_CPU1_TEST_9
  AW22  TEST_10  BI  = TP_CPU1_TEST_10
  AW24  BCLK0_DP  IN  = CLK_100M_CPU1_BCLK0_DP
  AW26  VCCIO(79)  POWER  = PVCCIO_CPU1
  AW60  VCCIN(231)  POWER  = PVCCIN_CPU1
  AW62  VSS(692)  GROUND  = GND
  AW64  RSVD(184)  BI  = TP_CPU1_RSVD_184
  AW66  VSS(691)  GROUND  = GND
  AW68  VSS(690)  GROUND  = GND
  AW70  VSS(689)  GROUND  = GND
  AW72  VSS(688)  GROUND  = GND
  AW74  VSS(687)  GROUND  = GND
  AW76  RSVD(183)  BI  = TP_CPU1_RSVD_183
  AW78  VSS(686)  GROUND  = GND
  AW80  DDR1_DQ(4)  BI  = M_H_DQ<4>
  AW82  VSS(685)  GROUND  = GND
  AW84  VSS(684)  GROUND  = GND
  AW86  VCCINPMAX(0)  POWER  = VSENSE_VCCINR2PMAX_CPU1
  AY3  UPI0_TX_DP(16)  OUT  = UPI_CPU1_CPU0_P0P0_DN<16>
  AY5  VSS(683)  GROUND  = GND
  AY7  UPI0_RX_DP(13)  IN  = UPI_CPU0_CPU1_P0P0_DP<13>
  AY9  UPI0_RX_DN(17)  IN  = UPI_CPU0_CPU1_P0P0_DN<17>
  AY11  VCCIO(36)  POWER  = PVCCIO_CPU1
  AY13  TEST_11  BI  = TP_CPU1_RSVD_TEST_11
  AY15  VSS(682)  GROUND  = GND
  AY17  VSS(681)  GROUND  = GND
  AY19  TEST_12  BI  = PD_CPU1_TEST12
  AY21  VSS(680)  GROUND  = GND
  AY23  VSS(679)  GROUND  = GND
  AY25  VSS(678)  GROUND  = GND
  AY27  VCCIO(78)  POWER  = PVCCIO_CPU1
  AY61  VCCIN(230)  POWER  = PVCCIN_CPU1
  AY63  VSS(677)  GROUND  = GND
  AY65  RSVD(182)  BI  = TP_CPU1_RSVD_182
  AY67  RSVD(181)  BI  = TP_CPU1_RSVD_181
  AY69  DDR2_ECC(3)  BI  = M_J_ECC<3>
  AY71  DDR2_DQS_DP(8)  BI  = M_J_DQS_DP<8>
  AY73  DDR2_ECC(5)  BI  = M_J_ECC<5>
  AY75  RSVD(180)  BI  = TP_CPU1_RSVD_180
  AY77  RSVD(179)  BI  = TP_CPU1_RSVD_179
  AY79  VSS(676)  GROUND  = GND
  AY81  VSS(675)  GROUND  = GND
  AY83  RSVD(255)  BI  = TP_CPU1_RSVD_255
  AY85  VSS_VCCIN_SENSE  POWER  = VSENSE_PVCCIN_CPU1_SKT_VRTN
  B3  RSVD(299)  BI  = TP_CPU1_RSVD_299
  B5  VSS(1250)  GROUND  = GND
  B7  RSVD(298)  BI  = TP_CPU1_RSVD_298
  B9  VSS(1253)  GROUND  = GND
  B11  CD_VPP(0)  POWER  = PVPP_GHJ
  B13  RSVD(296)  BI  = P1V8_MCP_CPU1
  B15  RSVD(295)  BI  = P1V8_MCP_CPU1
  B17  RSVD(294)  BI  = P1V8_MCP_CPU1
  B25  VSS(1180)  GROUND  = GND
  B27  DDR1_DQ(54)  BI  = M_H_DQ<54>
  B29  DDR1_DQ(49)  BI  = M_H_DQ<49>
  B31  VSS(1179)  GROUND  = GND
  B33  DDR1_DQ(46)  BI  = M_H_DQ<46>
  B35  DDR1_DQ(41)  BI  = M_H_DQ<41>
  B37  VSS(1178)  GROUND  = GND
  B39  DDR0_DQ(38)  BI  = M_G_DQ<38>
  B41  DDR0_DQ(33)  BI  = M_G_DQ<33>
  B43  VSS(1251)  GROUND  = GND
  B47  VCCD012(51)  POWER  = PVDDQ_GHJ
  B49  VCCD012(0)  POWER  = PVDDQ_GHJ
  B51  DDR0_CS_N(4)  OUT  = M_G_CS_N<4>
  B53  VCCD012(1)  POWER  = PVDDQ_GHJ
  B55  DDR0_CLK_DP(1)  OUT  = M_G_CLK_DP<1>
  B57  DDR0_CLK_DP(3)  OUT  = M_G_CLK_DP<3>
  B59  VCCD012(2)  POWER  = PVDDQ_GHJ
  B61  DDR0_ALERT_N  IN  = M_G_ALERT_N
  B63  DDR0_CKE(2)  OUT  = M_G_CKE<2>
  B71  VSS(1177)  GROUND  = GND
  B73  DDR1_DQS_DN(12)  BI  = M_H_DQS_DN<12>
  B75  VSS(1176)  GROUND  = GND
  B77  RSVD(293)  BI  = TP_CPU1_RSVD_293
  B79  VSS(1249)  GROUND  = GND
  B81  RSVD(292)  BI  = TP_CPU1_RSVD_292
  BA2  VSS(674)  GROUND  = GND
  BA4  UPI0_TX_DN(16)  OUT  = UPI_CPU1_CPU0_P0P0_DP<16>
  BA6  VSS(673)  GROUND  = GND
  BA8  UPI0_RX_DN(13)  IN  = UPI_CPU0_CPU1_P0P0_DN<13>
  BA10  UPI0_RX_DP(19)  IN  = UPI_CPU0_CPU1_P0P0_DN<19>
  BA12  VSS(672)  GROUND  = GND
  BA14  RSVD(178)  BI  = TP_CPU1_RSVD_178
  BA16  RSVD(177)  BI  = TP_CPU1_RSVD_177
  BA18  RSVD(176)  BI  = TP_CPU1_RSVD_176
  BA20  BIST_ENABLE  IN  = PD_CPU1_BIST_ENABLE
  BA22  RSVD(175)  BI  = TP_CPU1_RSVD_175
  BA24  VCCIO(35)  POWER  = PVCCIO_CPU1
  BA26  VCCIO(77)  POWER  = PVCCIO_CPU1
  BA60  VCCIN(229)  POWER  = PVCCIN_CPU1
  BA62  VSS(671)  GROUND  = GND
  BA64  RSVD(174)  BI  = TP_CPU1_RSVD_174
  BA66  RSVD(173)  BI  = TP_CPU1_RSVD_173
  BA68  VSS(670)  GROUND  = GND
  BA70  DDR2_ECC(7)  BI  = M_J_ECC<7>
  BA72  DDR2_ECC(1)  BI  = M_J_ECC<1>
  BA74  VSS(669)  GROUND  = GND
  BA76  RSVD(172)  BI  = TP_CPU1_RSVD_172
  BA78  RSVD(171)  BI  = TP_CPU1_RSVD_171
  BA80  VSS(668)  GROUND  = GND
  BA82  RSVD(170)  BI  = TP_CPU1_RSVD_170
  BA84  VSS(667)  GROUND  = GND
  BA86  VCCIN_SENSE  BI  = VSENSE_PVCCIN_CPU1_SKT_VSEN
  BB3  UPI0_TX_DN(17)  OUT  = UPI_CPU1_CPU0_P0P0_DN<17>
  BB5  VCCIO(34)  POWER  = PVCCIO_CPU1
  BB7  UPI0_RX_DP(14)  IN  = UPI_CPU0_CPU1_P0P0_DN<14>
  BB9  UPI0_RX_DP(17)  IN  = UPI_CPU0_CPU1_P0P0_DP<17>
  BB11  UPI0_RX_DN(19)  IN  = UPI_CPU0_CPU1_P0P0_DP<19>
  BB13  RSVD(169)  BI  = TP_CPU1_RSVD_169
  BB15  RSVD(168)  BI  = TP_CPU1_RSVD_168
  BB17  RSVD(167)  BI  = TP_CPU1_RSVD_167
  BB19  VSS(666)  GROUND  = GND
  BB21  RSVD(166)  BI  = TP_CPU1_RSVD_166
  BB23  VSS(665)  GROUND  = GND
  BB25  RSVD(165)  BI  = CLK_100M_CPU1_RC_REFCLK1_DN
  BB27  VCCIO(76)  POWER  = PVCCIO_CPU1
  BB61  VCCIN(228)  POWER  = PVCCIN_CPU1
  BB63  VSS(664)  GROUND  = GND
  BB65  RSVD(164)  BI  = TP_CPU1_RSVD_164
  BB67  RSVD(163)  BI  = TP_CPU1_RSVD_163
  BB69  VSS(663)  GROUND  = GND
  BB71  DDR2_DQS_DN(8)  BI  = M_J_DQS_DN<8>
  BB73  VSS(662)  GROUND  = GND
  BB75  VSS(661)  GROUND  = GND
  BB77  VSS(660)  GROUND  = GND
  BB79  VSS(659)  GROUND  = GND
  BB81  VSS(658)  GROUND  = GND
  BB83  VSS(657)  GROUND  = GND
  BB85  VCCIN(227)  POWER  = PVCCIN_CPU1
  BC2  UPI0_TX_DP(17)  OUT  = UPI_CPU1_CPU0_P0P0_DP<17>
  BC4  VSS(656)  GROUND  = GND
  BC6  UPI0_RX_DN(14)  IN  = UPI_CPU0_CPU1_P0P0_DP<14>
  BC8  VSS(655)  GROUND  = GND
  BC10  UPI0_RX_DP(18)  IN  = UPI_CPU0_CPU1_P0P0_DN<18>
  BC12  VSS(654)  GROUND  = GND
  BC14  RSVD(162)  BI  = TP_CPU1_RSVD_162
  BC16  VSS(653)  GROUND  = GND
  BC18  RSVD(161)  BI  = TP_CPU1_RSVD_161
  BC20  RSVD(160)  BI  = TP_CPU1_RSVD_160
  BC22  RSVD(159)  BI  = TP_CPU1_RSVD_159
  BC24  PWRGOOD  IN  = PWRGD_CPU1_G
  BC26  VCCIO(75)  POWER  = PVCCIO_CPU1
  BC60  VCCIN(226)  POWER  = PVCCIN_CPU1
  BC62  VCCIN(225)  POWER  = PVCCIN_CPU1
  BC64  RSVD(158)  BI  = TP_CPU1_RSVD_158
  BC66  RSVD(157)  BI  = TP_CPU1_RSVD_157
  BC68  RSVD(156)  BI  = TP_CPU1_RSVD_156
  BC70  VSS(652)  GROUND  = GND
  BC72  VSS(651)  GROUND  = GND
  BC74  VSS(650)  GROUND  = GND
  BC76  VSS(649)  GROUND  = GND
  BC78  VSS(648)  GROUND  = GND
  BC80  VSS(647)  GROUND  = GND
  BC82  VSS(646)  GROUND  = GND
  BC84  VCCIN(224)  POWER  = PVCCIN_CPU1
  BD3  UPI0_TX_DP(18)  OUT  = UPI_CPU1_CPU0_P0P0_DP<18>
  BD5  VSS(645)  GROUND  = GND
  BD7  UPI0_RX_DN(15)  IN  = UPI_CPU0_CPU1_P0P0_DN<15>
  BD9  UPI0_RX_DN(18)  IN  = UPI_CPU0_CPU1_P0P0_DP<18>
  BD11  VSS(644)  GROUND  = GND
  BD13  CD_VCC_CORE(12)  POWER  = PVCCMCP_CPU1
  BD15  VSS(643)  GROUND  = GND
  BD17  RSVD(155)  BI  = TP_CPU1_RSVD_155
  BD19  RSVD(154)  BI  = TP_CPU1_RSVD_154
  BD21  VSS(642)  GROUND  = GND
  BD23  BMCINIT  IN  = H_CPU1_BMCINIT
  BD25  RSVD(153)  BI  = CLK_100M_CPU1_RC_REFCLK1_DP
  BD27  VSS(641)  GROUND  = GND
  BD61  VCCIN(223)  POWER  = PVCCIN_CPU1
  BD63  VSS(640)  GROUND  = GND
  BD65  RSVD(152)  BI  = TP_CPU1_RSVD_152
  BD67  RSVD(151)  BI  = TP_CPU1_RSVD_151
  BD69  RSVD(150)  BI  = TP_CPU1_RSVD_150
  BD71  VSS(639)  GROUND  = GND
  BD73  VCCIN(222)  POWER  = PVCCIN_CPU1
  BD75  VCCIN(221)  POWER  = PVCCIN_CPU1
  BD77  VCCIN(220)  POWER  = PVCCIN_CPU1
  BD79  VCCIN(219)  POWER  = PVCCIN_CPU1
  BD81  VCCIN(218)  POWER  = PVCCIN_CPU1
  BD83  VCCIN(217)  POWER  = PVCCIN_CPU1
  BD85  VCCIN(216)  POWER  = PVCCIN_CPU1
  BE4  VSS(638)  GROUND  = GND
  BE6  VSS(637)  GROUND  = GND
  BE8  VSS(636)  GROUND  = GND
  BE10  VSS(635)  GROUND  = GND
  BE12  CD_VCC_CORE(11)  POWER  = PVCCMCP_CPU1
  BE14  CD_VCC_CORE(10)  POWER  = PVCCMCP_CPU1
  BE16  CD_HFI_REFCLK_DN  IN  = CLK_156M_OSC_CPU1_HFI_DN
  BE18  RSVD(149)  BI  = TP_CPU1_RSVD_149
  BE20  RSVD(148)  BI  = TP_CPU1_RSVD_148
  BE22  RSVD(147)  BI  = TP_CPU1_RSVD_147
  BE24  VCCIO(7)  POWER  = PVCCIO_CPU1
  BE26  VSS(634)  GROUND  = GND
  BE60  VCCIN(215)  POWER  = PVCCIN_CPU1
  BE62  VCCIN(214)  POWER  = PVCCIN_CPU1
  BE64  VSS(633)  GROUND  = GND
  BE66  VSS(632)  GROUND  = GND
  BE68  VSS(631)  GROUND  = GND
  BE70  VSS(630)  GROUND  = GND
  BE72  VCCIN(213)  POWER  = PVCCIN_CPU1
  BE74  VCCIN(212)  POWER  = PVCCIN_CPU1
  BE76  VCCIN(211)  POWER  = PVCCIN_CPU1
  BE78  VCCIN(210)  POWER  = PVCCIN_CPU1
  BE80  VCCIN(209)  POWER  = PVCCIN_CPU1
  BE82  VCCIN(208)  POWER  = PVCCIN_CPU1
  BE84  VCCIN(207)  POWER  = PVCCIN_CPU1
  BF3  UPI0_TX_DN(18)  OUT  = UPI_CPU1_CPU0_P0P0_DN<18>
  BF5  VSS_VCCIO_SENSE  POWER  = VSENSE_PVCCIO_CPU1_SKT_VRTN
  BF7  UPI0_RX_DP(15)  IN  = UPI_CPU0_CPU1_P0P0_DP<15>
  BF9  VSS(629)  GROUND  = GND
  BF11  CD_VCC_CORE(9)  POWER  = PVCCMCP_CPU1
  BF13  CD_VCC_CORE(8)  POWER  = PVCCMCP_CPU1
  BF15  VSS(628)  GROUND  = GND
  BF17  VSS(627)  GROUND  = GND
  BF19  VSS(626)  GROUND  = GND
  BF21  RSVD(146)  BI  = TP_CPU1_RSVD_146
  BF23  VCCIO(32)  POWER  = PVCCIO_CPU1
  BF25  VSS(625)  GROUND  = GND
  BF27  VCCIO(94)  POWER  = PVCCIO_CPU1
  BF61  VCCIN(206)  POWER  = PVCCIN_CPU1
  BF63  VSS(624)  GROUND  = GND
  BF65  VSS(623)  GROUND  = GND
  BF67  VSS(622)  GROUND  = GND
  BF69  VSS(621)  GROUND  = GND
  BF71  VSS(620)  GROUND  = GND
  BF73  VCCIN(205)  POWER  = PVCCIN_CPU1
  BF75  VCCIN(204)  POWER  = PVCCIN_CPU1
  BF77  VCCIN(203)  POWER  = PVCCIN_CPU1
  BF79  VCCIN(202)  POWER  = PVCCIN_CPU1
  BF81  VCCIN(201)  POWER  = PVCCIN_CPU1
  BF83  VCCIN(200)  POWER  = PVCCIN_CPU1
  BF85  VCCIN(199)  POWER  = PVCCIN_CPU1
  BG4  UPI0_TX_DN(19)  OUT  = UPI_CPU1_CPU0_P0P0_DP<19>
  BG6  VSS(619)  GROUND  = GND
  BG8  VSS(618)  GROUND  = GND
  BG10  VSS(617)  GROUND  = GND
  BG12  CD_VCC_CORE(7)  POWER  = PVCCMCP_CPU1
  BG14  CD_VCC_CORE(6)  POWER  = PVCCMCP_CPU1
  BG16  CD_HFI_REFCLK_DP  IN  = CLK_156M_OSC_CPU1_HFI_DP
  BG18  RSVD(145)  BI  = TP_CPU1_RSVD_145
  BG20  RSVD(144)  BI  = TP_CPU1_RSVD_144
  BG22  VSS(616)  GROUND  = GND
  BG24  VSS(615)  GROUND  = GND
  BG26  VCCIO(93)  POWER  = PVCCIO_CPU1
  BG60  VCCIN(198)  POWER  = PVCCIN_CPU1
  BG62  VCCIN(197)  POWER  = PVCCIN_CPU1
  BG64  VCCIN(196)  POWER  = PVCCIN_CPU1
  BG66  VCCIN(195)  POWER  = PVCCIN_CPU1
  BG68  VCCIN(194)  POWER  = PVCCIN_CPU1
  BG70  VCCIN(193)  POWER  = PVCCIN_CPU1
  BG72  VSS(614)  GROUND  = GND
  BG74  VSS(613)  GROUND  = GND
  BG76  VSS(612)  GROUND  = GND
  BG78  VSS(611)  GROUND  = GND
  BG80  VSS(610)  GROUND  = GND
  BG82  VSS(609)  GROUND  = GND
  BG84  VCCIN(192)  POWER  = PVCCIN_CPU1
  BH3  UPI0_TX_DP(19)  OUT  = UPI_CPU1_CPU0_P0P0_DN<19>
  BH5  VCCIO_SENSE  POWER  = VSENSE_PVCCIO_CPU1_SKT_VSEN
  BH7  VSS(608)  GROUND  = GND
  BH9  VSS(607)  GROUND  = GND
  BH11  VSS(606)  GROUND  = GND
  BH13  CD_VCC_CORE(5)  POWER  = PVCCMCP_CPU1
  BH15  VSS(605)  GROUND  = GND
  BH17  VSS(141)  GROUND  = GND
  BH19  RSVD(143)  BI  = PVCCMCP_CPU1
  BH21  VSS(604)  GROUND  = GND
  BH23  CD_HFI1_I2CDAT  BI  = TP_CD_HFI1_CPU1_I2CDAT
  BH25  VCCIO(92)  POWER  = PVCCIO_CPU1
  BH27  VCCIO(91)  POWER  = PVCCIO_CPU1
  BH61  VCCIN(191)  POWER  = PVCCIN_CPU1
  BH63  VCCIN(190)  POWER  = PVCCIN_CPU1
  BH65  VCCIN(189)  POWER  = PVCCIN_CPU1
  BH67  VCCIN(188)  POWER  = PVCCIN_CPU1
  BH69  VCCIN(187)  POWER  = PVCCIN_CPU1
  BH71  VCCIN(186)  POWER  = PVCCIN_CPU1
  BH73  VCCIN(185)  POWER  = PVCCIN_CPU1
  BH75  VCCIN(184)  POWER  = PVCCIN_CPU1
  BH77  VCCIN(183)  POWER  = PVCCIN_CPU1
  BH79  VCCIN(182)  POWER  = PVCCIN_CPU1
  BH81  VCCIN(181)  POWER  = PVCCIN_CPU1
  BH83  VCCIN(180)  POWER  = PVCCIN_CPU1
  BJ4  VSS(603)  GROUND  = GND
  BJ6  VSS(602)  GROUND  = GND
  BJ8  PE2_RX_DP(14)  IN  = TP_P3E_CPU1_PE2_RSR_RXP<14>
  BJ10  PE2_RX_DP(15)  IN  = TP_P3E_CPU1_PE2_RSR_RXP<15>
  BJ12  CD_VCC_CORE(4)  POWER  = PVCCMCP_CPU1
  BJ14  CD_VCC_CORE(3)  POWER  = PVCCMCP_CPU1
  BJ16  RSVD(142)  BI  = PVCCMCP_CPU1
  BJ18  RSVD(141)  BI  = PVCCMCP_CPU1
  BJ20  RSVD(140)  BI  = PVCCMCP_CPU1
  BJ22  CD_HFI1_I2CCLK  BI  = TP_CD_HFI1_CPU1_I2CLK
  BJ24  VCCIO(31)  POWER  = PVCCIO_CPU1
  BJ26  VCCIO(90)  POWER  = PVCCIO_CPU1
  BJ60  VCCIN(179)  POWER  = PVCCIN_CPU1
  BJ62  VCCIN(178)  POWER  = PVCCIN_CPU1
  BJ64  VCCIN(177)  POWER  = PVCCIN_CPU1
  BJ66  VCCIN(176)  POWER  = PVCCIN_CPU1
  BJ68  VCCIN(175)  POWER  = PVCCIN_CPU1
  BJ70  VCCIN(174)  POWER  = PVCCIN_CPU1
  BJ72  VCCIN(173)  POWER  = PVCCIN_CPU1
  BJ74  VCCIN(172)  POWER  = PVCCIN_CPU1
  BJ76  VCCIN(171)  POWER  = PVCCIN_CPU1
  BJ78  VCCIN(170)  POWER  = PVCCIN_CPU1
  BJ80  VCCIN(169)  POWER  = PVCCIN_CPU1
  BJ82  VCCIN(168)  POWER  = PVCCIN_CPU1
  BJ84  VCCIN(167)  POWER  = PVCCIN_CPU1
  BK3  VSS(601)  GROUND  = GND
  BK5  PE2_TX_DP(15)  OUT  = TP_P3E_CPU1_PE2_RSR_TXP<15>
  BK7  VSS(600)  GROUND  = GND
  BK9  PE2_RX_DN(15)  IN  = TP_P3E_CPU1_PE2_RSR_RXN<15>
  BK11  VSS(599)  GROUND  = GND
  BK13  CD_VCC_CORE(2)  POWER  = PVCCMCP_CPU1
  BK15  CD_VCC_CORE(1)  POWER  = PVCCMCP_CPU1
  BK17  RSVD(139)  BI  = PVCCMCP_CPU1
  BK19  VSS(598)  GROUND  = GND
  BK21  CD_HFI0_LED_N  OUT  = TP_LED_CPU1_CD_HFI0_N
  BK23  CD_HFI1_RESET_N  OUT  = TP_CD_HFI1_CPU1_RESET_N
  BK25  VCCIO(89)  POWER  = PVCCIO_CPU1
  BK27  VCCIO(88)  POWER  = PVCCIO_CPU1
  BK61  VCCIN(166)  POWER  = PVCCIN_CPU1
  BK63  VCCIN(165)  POWER  = PVCCIN_CPU1
  BK65  VCCIN(164)  POWER  = PVCCIN_CPU1
  BK67  VCCIN(163)  POWER  = PVCCIN_CPU1
  BK69  VCCIN(162)  POWER  = PVCCIN_CPU1
  BK71  VCCIN(161)  POWER  = PVCCIN_CPU1
  BK73  VCCIN(160)  POWER  = PVCCIN_CPU1
  BK75  VCCIN(159)  POWER  = PVCCIN_CPU1
  BK77  VCCIN(158)  POWER  = PVCCIN_CPU1
  BK79  VCCIN(157)  POWER  = PVCCIN_CPU1
  BK81  VCCIN(156)  POWER  = PVCCIN_CPU1
  BK83  VCCIN(155)  POWER  = PVCCIN_CPU1
  BL4  PE2_TX_DN(14)  OUT  = TP_P3E_CPU1_PE2_RSR_TXN<14>
